(kicad_pcb
	(version 20260206)
	(generator "pcbnew")
	(generator_version "10.0")
	(general
		(thickness 1.6)
		(legacy_teardrops no)
	)
	(paper "A4")
	(title_block
		(title "panther-plus-userver — 13130-1b_20150205.brd")
		(comment 1 "Honey Badger (Wiwynn) / footprints 96-104 of 1509")
	)
	(layers
		(0 "F.Cu" signal "TOP")
		(4 "In1.Cu" signal "L2")
		(6 "In2.Cu" signal "L3")
		(8 "In3.Cu" signal "L4")
		(10 "In4.Cu" signal "L5")
		(12 "In5.Cu" signal "L6")
		(14 "In6.Cu" signal "L7")
		(16 "In7.Cu" signal "L8")
		(18 "In8.Cu" signal "L9")
		(20 "In9.Cu" signal "L10")
		(22 "In10.Cu" signal "L11")
		(2 "B.Cu" signal "BOTTOM")
		(9 "F.Adhes" user "F.Adhesive")
		(11 "B.Adhes" user "B.Adhesive")
		(13 "F.Paste" user "Package Geometry/Pastemask Top")
		(15 "B.Paste" user "Package Geometry/Pastemask Bottom")
		(5 "F.SilkS" user "Ref Des/Silkscreen Top")
		(7 "B.SilkS" user "Ref Des/Silkscreen Bottom")
		(1 "F.Mask" user "Board Geometry/Soldermask Top")
		(3 "B.Mask" user "Board Geometry/Soldermask Bottom")
		(17 "Dwgs.User" user "User.Drawings")
		(19 "Cmts.User" user "User.Comments")
		(21 "Eco1.User" user "User.Eco1")
		(23 "Eco2.User" user "User.Eco2")
		(25 "Edge.Cuts" user "Board Geometry/Outline")
		(27 "Margin" user)
		(31 "F.CrtYd" user "Package Geometry/Place Bound Top")
		(29 "B.CrtYd" user "Package Geometry/Place Bound Bottom")
		(35 "F.Fab" user "Ref Des/Assembly Top")
		(33 "B.Fab" user "Ref Des/Assembly Bottom")
	)
	(footprint ""
		(layer "F.Cu")
		(at 194.31 -36.2966 -90)
		(property "Reference" "PR137"
			(at 0 0 270)
			(layer "F.SilkS")
			(hide yes)
			(effects
				(font
					(size 1.27 1.27)
				)
			)
		)
		(property "Value" "0R2J-2-GP"
			(at 1.7907 -1.1176 270)
			(unlocked yes)
			(layer "F.Fab")
			(hide yes)
			(effects
				(font
					(size 1.016 1.016)
					(thickness 0.1524)
				)
			)
		)
		(property "Device Type" "R402H16"
			(at 1.7907 -2.6416 270)
			(unlocked yes)
			(layer "F.Fab")
			(hide yes)
			(effects
				(font
					(size 1.016 1.016)
					(thickness 0.1524)
				)
			)
		)
		(duplicate_pad_numbers_are_jumpers no)
		(fp_rect
			(start -0.381 0.8382)
			(end 0.381 -0.8382)
			(stroke
				(width 0)
				(type default)
			)
			(fill no)
			(layer "F.CrtYd")
		)
		(fp_rect
			(start -0.381 0.8382)
			(end 0.381 -0.8382)
			(stroke
				(width 0)
				(type default)
			)
			(fill no)
			(layer "F.Fab")
		)
		(pad "1" smd custom
			(at 0 -0.4318 270)
			(size 0.127 0.127)
			(layers "F.Cu" "F.Mask" "F.Paste")
			(net "VR_PVDDR_A_VDD")
			(options
				(clearance outline)
				(anchor circle)
			)
			(primitives
				(gr_poly
					(pts
						(arc
							(start -0.2032 -0.2794)
							(mid -0.239121 -0.264521)
							(end -0.254 -0.2286)
						)
						(arc
							(start -0.254 0.2286)
							(mid -0.239121 0.264521)
							(end -0.2032 0.2794)
						)
						(arc
							(start 0.2032 0.2794)
							(mid 0.239121 0.264521)
							(end 0.254 0.2286)
						)
						(arc
							(start 0.254 -0.2286)
							(mid 0.239121 -0.264521)
							(end 0.2032 -0.2794)
						)
					)
					(width 0)
					(fill yes)
				)
			)
		)
		(pad "2" smd custom
			(at 0 0.4318 270)
			(size 0.127 0.127)
			(layers "F.Cu" "F.Mask" "F.Paste")
			(net "VR_PVDDR_A_PWM3")
			(options
				(clearance outline)
				(anchor circle)
			)
			(primitives
				(gr_poly
					(pts
						(arc
							(start -0.2032 -0.2794)
							(mid -0.239121 -0.264521)
							(end -0.254 -0.2286)
						)
						(arc
							(start -0.254 0.2286)
							(mid -0.239121 0.264521)
							(end -0.2032 0.2794)
						)
						(arc
							(start 0.2032 0.2794)
							(mid 0.239121 0.264521)
							(end 0.254 0.2286)
						)
						(arc
							(start 0.254 -0.2286)
							(mid 0.239121 -0.264521)
							(end 0.2032 -0.2794)
						)
					)
					(width 0)
					(fill yes)
				)
			)
		)
	)
	(footprint ""
		(layer "F.Cu")
		(at 29.845 -51.816 90)
		(property "Reference" "PC129"
			(at 0 0 90)
			(layer "F.SilkS")
			(hide yes)
			(effects
				(font
					(size 1.27 1.27)
				)
			)
		)
		(property "Value" "SC10U6D3V5KX-4GP"
			(at 0 -4.9022 90)
			(unlocked yes)
			(layer "F.Fab")
			(hide yes)
			(effects
				(font
					(size 1.016 1.016)
					(thickness 0.1524)
				)
			)
		)
		(property "Device Type" "C805H58"
			(at 0 -6.8072 90)
			(unlocked yes)
			(layer "F.Fab")
			(hide yes)
			(effects
				(font
					(size 1.016 1.016)
					(thickness 0.1524)
				)
			)
		)
		(duplicate_pad_numbers_are_jumpers no)
		(fp_line
			(start 0.6096 0)
			(end -0.6096 0)
			(stroke
				(width 0.3048)
				(type default)
			)
			(layer "F.SilkS")
		)
		(fp_poly
			(pts
				(xy -0.9017 1.4351) (xy 0.9017 1.4351) (xy 0.9017 -1.4351) (xy -0.9017 -1.4351)
			)
			(stroke
				(width 0)
				(type default)
			)
			(fill no)
			(layer "F.CrtYd")
		)
		(fp_poly
			(pts
				(xy 0.9017 1.4351) (xy 0.9017 -1.4351) (xy -0.9017 -1.4351) (xy -0.9017 1.4351)
			)
			(stroke
				(width 0)
				(type default)
			)
			(fill no)
			(layer "F.Fab")
		)
		(pad "1" smd rect
			(at 0 -0.8382 90)
			(size 1.5494 0.9398)
			(layers "F.Cu" "F.Mask" "F.Paste")
			(net "P1V5_STBY_IN")
		)
		(pad "2" smd rect
			(at 0 0.8382 90)
			(size 1.5494 0.9398)
			(layers "F.Cu" "F.Mask" "F.Paste")
			(net "GND")
		)
	)
	(footprint ""
		(layer "F.Cu")
		(at 67.056 -13.462 90)
		(property "Reference" "R474"
			(at 0 0 90)
			(layer "F.SilkS")
			(hide yes)
			(effects
				(font
					(size 1.27 1.27)
				)
			)
		)
		(property "Value" "4K7R2F-GP"
			(at 1.7907 -1.1176 90)
			(unlocked yes)
			(layer "F.Fab")
			(hide yes)
			(effects
				(font
					(size 1.016 1.016)
					(thickness 0.1524)
				)
			)
		)
		(property "Device Type" "R402H16"
			(at 1.7907 -2.6416 90)
			(unlocked yes)
			(layer "F.Fab")
			(hide yes)
			(effects
				(font
					(size 1.016 1.016)
					(thickness 0.1524)
				)
			)
		)
		(duplicate_pad_numbers_are_jumpers no)
		(fp_rect
			(start -0.381 0.8382)
			(end 0.381 -0.8382)
			(stroke
				(width 0)
				(type default)
			)
			(fill no)
			(layer "F.CrtYd")
		)
		(fp_rect
			(start -0.381 0.8382)
			(end 0.381 -0.8382)
			(stroke
				(width 0)
				(type default)
			)
			(fill no)
			(layer "F.Fab")
		)
		(pad "1" smd custom
			(at 0 -0.4318 90)
			(size 0.127 0.127)
			(layers "F.Cu" "F.Mask" "F.Paste")
			(net "P3V3")
			(options
				(clearance outline)
				(anchor circle)
			)
			(primitives
				(gr_poly
					(pts
						(arc
							(start -0.2032 -0.2794)
							(mid -0.239121 -0.264521)
							(end -0.254 -0.2286)
						)
						(arc
							(start -0.254 0.2286)
							(mid -0.239121 0.264521)
							(end -0.2032 0.2794)
						)
						(arc
							(start 0.2032 0.2794)
							(mid 0.239121 0.264521)
							(end 0.254 0.2286)
						)
						(arc
							(start 0.254 -0.2286)
							(mid 0.239121 -0.264521)
							(end 0.2032 -0.2794)
						)
					)
					(width 0)
					(fill yes)
				)
			)
		)
		(pad "2" smd custom
			(at 0 0.4318 90)
			(size 0.127 0.127)
			(layers "F.Cu" "F.Mask" "F.Paste")
			(net "HOST_LV_RSTBTN#")
			(options
				(clearance outline)
				(anchor circle)
			)
			(primitives
				(gr_poly
					(pts
						(arc
							(start -0.2032 -0.2794)
							(mid -0.239121 -0.264521)
							(end -0.254 -0.2286)
						)
						(arc
							(start -0.254 0.2286)
							(mid -0.239121 0.264521)
							(end -0.2032 0.2794)
						)
						(arc
							(start 0.2032 0.2794)
							(mid 0.239121 0.264521)
							(end 0.254 0.2286)
						)
						(arc
							(start 0.254 -0.2286)
							(mid 0.239121 -0.264521)
							(end 0.2032 -0.2794)
						)
					)
					(width 0)
					(fill yes)
				)
			)
		)
	)
	(footprint ""
		(layer "F.Cu")
		(at 181.356 -17.653 180)
		(property "Reference" "PR168"
			(at 0 0 180)
			(layer "F.SilkS")
			(hide yes)
			(effects
				(font
					(size 1.27 1.27)
				)
			)
		)
		(property "Value" "20KR2F-L-GP"
			(at 0.064008 -3.993896 180)
			(unlocked yes)
			(layer "F.Fab")
			(hide yes)
			(effects
				(font
					(size 1.016 1.016)
					(thickness 0.1524)
				)
			)
		)
		(property "Device Type" "R402H16"
			(at 0.064008 -5.517896 180)
			(unlocked yes)
			(layer "F.Fab")
			(hide yes)
			(effects
				(font
					(size 1.016 1.016)
					(thickness 0.1524)
				)
			)
		)
		(duplicate_pad_numbers_are_jumpers no)
		(fp_rect
			(start -0.381 0.8382)
			(end 0.381 -0.8382)
			(stroke
				(width 0)
				(type default)
			)
			(fill no)
			(layer "F.CrtYd")
		)
		(fp_rect
			(start -0.381 0.8382)
			(end 0.381 -0.8382)
			(stroke
				(width 0)
				(type default)
			)
			(fill no)
			(layer "F.Fab")
		)
		(pad "1" smd custom
			(at 0 -0.4318 180)
			(size 0.127 0.127)
			(layers "F.Cu" "F.Mask" "F.Paste")
			(net "PV_VTT_DDR_B_REFIN")
			(options
				(clearance outline)
				(anchor circle)
			)
			(primitives
				(gr_poly
					(pts
						(arc
							(start -0.2032 -0.2794)
							(mid -0.239121 -0.264521)
							(end -0.254 -0.2286)
						)
						(arc
							(start -0.254 0.2286)
							(mid -0.239121 0.264521)
							(end -0.2032 0.2794)
						)
						(arc
							(start 0.2032 0.2794)
							(mid 0.239121 0.264521)
							(end 0.254 0.2286)
						)
						(arc
							(start 0.254 -0.2286)
							(mid 0.239121 -0.264521)
							(end 0.2032 -0.2794)
						)
					)
					(width 0)
					(fill yes)
				)
			)
		)
		(pad "2" smd custom
			(at 0 0.4318 180)
			(size 0.127 0.127)
			(layers "F.Cu" "F.Mask" "F.Paste")
			(net "GND")
			(options
				(clearance outline)
				(anchor circle)
			)
			(primitives
				(gr_poly
					(pts
						(arc
							(start -0.2032 -0.2794)
							(mid -0.239121 -0.264521)
							(end -0.254 -0.2286)
						)
						(arc
							(start -0.254 0.2286)
							(mid -0.239121 0.264521)
							(end -0.2032 0.2794)
						)
						(arc
							(start 0.2032 0.2794)
							(mid 0.239121 0.264521)
							(end 0.254 0.2286)
						)
						(arc
							(start 0.254 -0.2286)
							(mid 0.239121 -0.264521)
							(end 0.2032 -0.2794)
						)
					)
					(width 0)
					(fill yes)
				)
			)
		)
	)
	(footprint ""
		(layer "F.Cu")
		(at 174.3456 -44.3992 180)
		(property "Reference" "PC209"
			(at 0 0 180)
			(layer "F.SilkS")
			(hide yes)
			(effects
				(font
					(size 1.27 1.27)
				)
			)
		)
		(property "Value" "SC1U6D3V2KX-GP"
			(at 1.8923 -1.2065 180)
			(unlocked yes)
			(layer "F.Fab")
			(hide yes)
			(effects
				(font
					(size 1.016 1.016)
					(thickness 0.1524)
				)
			)
		)
		(property "Device Type" "C402H22"
			(at 1.8923 -2.7305 180)
			(unlocked yes)
			(layer "F.Fab")
			(hide yes)
			(effects
				(font
					(size 1.016 1.016)
					(thickness 0.1524)
				)
			)
		)
		(duplicate_pad_numbers_are_jumpers no)
		(fp_rect
			(start -0.381 0.7366)
			(end 0.381 -0.7366)
			(stroke
				(width 0)
				(type default)
			)
			(fill no)
			(layer "F.CrtYd")
		)
		(fp_rect
			(start -0.381 0.7366)
			(end 0.381 -0.7366)
			(stroke
				(width 0)
				(type default)
			)
			(fill no)
			(layer "F.Fab")
		)
		(pad "1" smd custom
			(at 0 -0.4572 180)
			(size 0.1143 0.1143)
			(layers "F.Cu" "F.Mask" "F.Paste")
			(net "P3V3_STBY")
			(options
				(clearance outline)
				(anchor circle)
			)
			(primitives
				(gr_poly
					(pts
						(arc
							(start -0.254 -0.1778)
							(mid -0.239121 -0.213721)
							(end -0.2032 -0.2286)
						)
						(arc
							(start 0.2032 -0.2286)
							(mid 0.239121 -0.213721)
							(end 0.254 -0.1778)
						)
						(arc
							(start 0.254 0.1778)
							(mid 0.239121 0.213721)
							(end 0.2032 0.2286)
						)
						(arc
							(start -0.2032 0.2286)
							(mid -0.239121 0.213721)
							(end -0.254 0.1778)
						)
					)
					(width 0)
					(fill yes)
				)
			)
		)
		(pad "2" smd custom
			(at 0 0.4572 180)
			(size 0.1143 0.1143)
			(layers "F.Cu" "F.Mask" "F.Paste")
			(net "GND")
			(options
				(clearance outline)
				(anchor circle)
			)
			(primitives
				(gr_poly
					(pts
						(arc
							(start -0.254 -0.1778)
							(mid -0.239121 -0.213721)
							(end -0.2032 -0.2286)
						)
						(arc
							(start 0.2032 -0.2286)
							(mid 0.239121 -0.213721)
							(end 0.254 -0.1778)
						)
						(arc
							(start 0.254 0.1778)
							(mid 0.239121 0.213721)
							(end 0.2032 0.2286)
						)
						(arc
							(start -0.2032 0.2286)
							(mid -0.239121 0.213721)
							(end -0.254 0.1778)
						)
					)
					(width 0)
					(fill yes)
				)
			)
		)
	)
	(footprint ""
		(layer "F.Cu")
		(at 111.379 -70.612 90)
		(property "Reference" "C6"
			(at 0 0 90)
			(layer "F.SilkS")
			(hide yes)
			(effects
				(font
					(size 1.27 1.27)
				)
			)
		)
		(property "Value" "SCD1U10V2KX-5GP"
			(at 1.1811 -2.7051 90)
			(unlocked yes)
			(layer "F.Fab")
			(hide yes)
			(effects
				(font
					(size 1.016 1.016)
					(thickness 0.1524)
				)
			)
		)
		(property "Device Type" "C402H22"
			(at 1.1811 -4.2291 90)
			(unlocked yes)
			(layer "F.Fab")
			(hide yes)
			(effects
				(font
					(size 1.016 1.016)
					(thickness 0.1524)
				)
			)
		)
		(duplicate_pad_numbers_are_jumpers no)
		(fp_rect
			(start -0.381 0.7366)
			(end 0.381 -0.7366)
			(stroke
				(width 0)
				(type default)
			)
			(fill no)
			(layer "F.CrtYd")
		)
		(fp_rect
			(start -0.381 0.7366)
			(end 0.381 -0.7366)
			(stroke
				(width 0)
				(type default)
			)
			(fill no)
			(layer "F.Fab")
		)
		(pad "1" smd custom
			(at 0 -0.4572 90)
			(size 0.1143 0.1143)
			(layers "F.Cu" "F.Mask" "F.Paste")
			(net "CLK_GEN_OUT_R")
			(options
				(clearance outline)
				(anchor circle)
			)
			(primitives
				(gr_poly
					(pts
						(arc
							(start -0.254 -0.1778)
							(mid -0.239121 -0.213721)
							(end -0.2032 -0.2286)
						)
						(arc
							(start 0.2032 -0.2286)
							(mid 0.239121 -0.213721)
							(end 0.254 -0.1778)
						)
						(arc
							(start 0.254 0.1778)
							(mid 0.239121 0.213721)
							(end 0.2032 0.2286)
						)
						(arc
							(start -0.2032 0.2286)
							(mid -0.239121 0.213721)
							(end -0.254 0.1778)
						)
					)
					(width 0)
					(fill yes)
				)
			)
		)
		(pad "2" smd custom
			(at 0 0.4572 90)
			(size 0.1143 0.1143)
			(layers "F.Cu" "F.Mask" "F.Paste")
			(net "GND")
			(options
				(clearance outline)
				(anchor circle)
			)
			(primitives
				(gr_poly
					(pts
						(arc
							(start -0.254 -0.1778)
							(mid -0.239121 -0.213721)
							(end -0.2032 -0.2286)
						)
						(arc
							(start 0.2032 -0.2286)
							(mid 0.239121 -0.213721)
							(end 0.254 -0.1778)
						)
						(arc
							(start 0.254 0.1778)
							(mid 0.239121 0.213721)
							(end 0.2032 0.2286)
						)
						(arc
							(start -0.2032 0.2286)
							(mid -0.239121 0.213721)
							(end -0.254 0.1778)
						)
					)
					(width 0)
					(fill yes)
				)
			)
		)
	)
	(footprint ""
		(layer "F.Cu")
		(at 107.061 -19.939 -90)
		(property "Reference" "R165"
			(at 0 0 270)
			(layer "F.SilkS")
			(hide yes)
			(effects
				(font
					(size 1.27 1.27)
				)
			)
		)
		(property "Value" "0R2J-2-GP"
			(at 0.064008 -3.993896 270)
			(unlocked yes)
			(layer "F.Fab")
			(hide yes)
			(effects
				(font
					(size 1.016 1.016)
					(thickness 0.1524)
				)
			)
		)
		(property "Device Type" "R402H16"
			(at 0.064008 -5.517896 270)
			(unlocked yes)
			(layer "F.Fab")
			(hide yes)
			(effects
				(font
					(size 1.016 1.016)
					(thickness 0.1524)
				)
			)
		)
		(duplicate_pad_numbers_are_jumpers no)
		(fp_rect
			(start -0.381 0.8382)
			(end 0.381 -0.8382)
			(stroke
				(width 0)
				(type default)
			)
			(fill no)
			(layer "F.CrtYd")
		)
		(fp_rect
			(start -0.381 0.8382)
			(end 0.381 -0.8382)
			(stroke
				(width 0)
				(type default)
			)
			(fill no)
			(layer "F.Fab")
		)
		(pad "1" smd custom
			(at 0 -0.4318 270)
			(size 0.127 0.127)
			(layers "F.Cu" "F.Mask" "F.Paste")
			(net "M_B_RESET#")
			(options
				(clearance outline)
				(anchor circle)
			)
			(primitives
				(gr_poly
					(pts
						(arc
							(start -0.2032 -0.2794)
							(mid -0.239121 -0.264521)
							(end -0.254 -0.2286)
						)
						(arc
							(start -0.254 0.2286)
							(mid -0.239121 0.264521)
							(end -0.2032 0.2794)
						)
						(arc
							(start 0.2032 0.2794)
							(mid 0.239121 0.264521)
							(end 0.254 0.2286)
						)
						(arc
							(start 0.254 -0.2286)
							(mid 0.239121 -0.264521)
							(end 0.2032 -0.2794)
						)
					)
					(width 0)
					(fill yes)
				)
			)
		)
		(pad "2" smd custom
			(at 0 0.4318 270)
			(size 0.127 0.127)
			(layers "F.Cu" "F.Mask" "F.Paste")
			(net "M_B_R_RESET#")
			(options
				(clearance outline)
				(anchor circle)
			)
			(primitives
				(gr_poly
					(pts
						(arc
							(start -0.2032 -0.2794)
							(mid -0.239121 -0.264521)
							(end -0.254 -0.2286)
						)
						(arc
							(start -0.254 0.2286)
							(mid -0.239121 0.264521)
							(end -0.2032 0.2794)
						)
						(arc
							(start 0.2032 0.2794)
							(mid 0.239121 0.264521)
							(end 0.254 0.2286)
						)
						(arc
							(start 0.254 -0.2286)
							(mid 0.239121 -0.264521)
							(end 0.2032 -0.2794)
						)
					)
					(width 0)
					(fill yes)
				)
			)
		)
	)
	(footprint ""
		(layer "F.Cu")
		(at 158.623 -12.955778 180)
		(property "Reference" "C370"
			(at 0 0 180)
			(layer "F.SilkS")
			(hide yes)
			(effects
				(font
					(size 1.27 1.27)
				)
			)
		)
		(property "Value" "SC47U6D3V5MX-1-GP"
			(at 0 -4.9022 180)
			(unlocked yes)
			(layer "F.Fab")
			(hide yes)
			(effects
				(font
					(size 1.016 1.016)
					(thickness 0.1524)
				)
			)
		)
		(property "Device Type" "C805H54"
			(at 0 -6.8072 180)
			(unlocked yes)
			(layer "F.Fab")
			(hide yes)
			(effects
				(font
					(size 1.016 1.016)
					(thickness 0.1524)
				)
			)
		)
		(duplicate_pad_numbers_are_jumpers no)
		(fp_line
			(start 0.6096 0)
			(end -0.6096 0)
			(stroke
				(width 0.3048)
				(type default)
			)
			(layer "F.SilkS")
		)
		(fp_poly
			(pts
				(xy -0.9017 1.4351) (xy 0.9017 1.4351) (xy 0.9017 -1.4351) (xy -0.9017 -1.4351)
			)
			(stroke
				(width 0)
				(type default)
			)
			(fill no)
			(layer "F.CrtYd")
		)
		(fp_poly
			(pts
				(xy 0.9017 1.4351) (xy 0.9017 -1.4351) (xy -0.9017 -1.4351) (xy -0.9017 1.4351)
			)
			(stroke
				(width 0)
				(type default)
			)
			(fill no)
			(layer "F.Fab")
		)
		(pad "1" smd rect
			(at 0 -0.8382 180)
			(size 1.5494 0.9398)
			(layers "F.Cu" "F.Mask" "F.Paste")
			(net "PV_VDDR")
		)
		(pad "2" smd rect
			(at 0 0.8382 180)
			(size 1.5494 0.9398)
			(layers "F.Cu" "F.Mask" "F.Paste")
			(net "GND")
		)
	)
	(footprint ""
		(layer "F.Cu")
		(at 130.429 -48.514 180)
		(property "Reference" "R10"
			(at 0 0 180)
			(layer "F.SilkS")
			(hide yes)
			(effects
				(font
					(size 1.27 1.27)
				)
			)
		)
		(property "Value" "3K3R3F-GP"
			(at -0.0254 -2.0193 180)
			(unlocked yes)
			(layer "F.Fab")
			(hide yes)
			(effects
				(font
					(size 1.016 1.016)
					(thickness 0.1524)
				)
			)
		)
		(property "Device Type" "R603H22"
			(at -0.0254 -3.5433 180)
			(unlocked yes)
			(layer "F.Fab")
			(hide yes)
			(effects
				(font
					(size 1.016 1.016)
					(thickness 0.1524)
				)
			)
		)
		(duplicate_pad_numbers_are_jumpers no)
		(fp_line
			(start 0.4318 0)
			(end 0.2032 0)
			(stroke
				(width 0.2032)
				(type default)
			)
			(layer "F.SilkS")
		)
		(fp_line
			(start -0.2032 0)
			(end -0.4191 0)
			(stroke
				(width 0.2032)
				(type default)
			)
			(layer "F.SilkS")
		)
		(fp_rect
			(start -0.635 1.1811)
			(end 0.635 -1.1811)
			(stroke
				(width 0)
				(type default)
			)
			(fill no)
			(layer "F.CrtYd")
		)
		(fp_rect
			(start -0.635 1.1811)
			(end 0.635 -1.1811)
			(stroke
				(width 0)
				(type default)
			)
			(fill no)
			(layer "F.Fab")
		)
		(pad "1" smd custom
			(at 0 -0.6604 180)
			(size 0.19685 0.19685)
			(layers "F.Cu" "F.Mask" "F.Paste")
			(net "P3V3")
			(options
				(clearance outline)
				(anchor circle)
			)
			(primitives
				(gr_poly
					(pts
						(arc
							(start 0.508 -0.2921)
							(mid 0.478242 -0.363942)
							(end 0.4064 -0.3937)
						)
						(arc
							(start -0.4064 -0.3937)
							(mid -0.478242 -0.363942)
							(end -0.508 -0.2921)
						)
						(arc
							(start -0.508 0.2921)
							(mid -0.478242 0.363942)
							(end -0.4064 0.3937)
						)
						(arc
							(start 0.4064 0.3937)
							(mid 0.478242 0.363942)
							(end 0.508 0.2921)
						)
					)
					(width 0)
					(fill yes)
				)
			)
		)
		(pad "2" smd custom
			(at 0 0.6604 180)
			(size 0.19685 0.19685)
			(layers "F.Cu" "F.Mask" "F.Paste")
			(net "MEMORY_FPGA_HOT#")
			(options
				(clearance outline)
				(anchor circle)
			)
			(primitives
				(gr_poly
					(pts
						(arc
							(start 0.508 -0.2921)
							(mid 0.478242 -0.363942)
							(end 0.4064 -0.3937)
						)
						(arc
							(start -0.4064 -0.3937)
							(mid -0.478242 -0.363942)
							(end -0.508 -0.2921)
						)
						(arc
							(start -0.508 0.2921)
							(mid -0.478242 0.363942)
							(end -0.4064 0.3937)
						)
						(arc
							(start 0.4064 0.3937)
							(mid 0.478242 0.363942)
							(end 0.508 0.2921)
						)
					)
					(width 0)
					(fill yes)
				)
			)
		)
	)
)
